# S9S_MB_2U (Grand Teton) — schematic netlist excerpt (pin names and nets, part order shuffled) for the footprints in the layout excerpt that follows; sources: Cadence DE-HDL packaged netlist, KiCad conversion of 03242023_DA0F0TMBIJ0_F0T_Motherboard_J_brd_V01_OCP.brd

R3877  Q_RES  49.9 1% CHIP  pkg 0402LF  page 84 : A = I3C_SPD_DDRABCD_CPU0_LVC1_SCL_2 ; B = I3C_SPD_DDRABCD_CPU0_LVC1_SCL
C320  Q_CAP  47UF 4V 20% X6S  pkg C0805  page 78 : A = PVCCIN_CPU1 ; B = GND
C94  Q_CAP  10UF 16V 10% X6S  pkg C0805  page 106 : A = P12V_S3_AUX_CPU1_NVDIMM ; B = GND

(kicad_pcb
	(version 20260206)
	(generator "pcbnew")
	(generator_version "10.0")
	(general
		(thickness 1.6)
		(legacy_teardrops no)
	)
	(paper "A4")
	(title_block
		(title "03242023_DA0F0TMBIJ0_F0T_Motherboard_J_brd_V01_OCP.brd")
		(comment 1 "Grand Teton / footprints 5085-5087 of 6105")
	)
	(layers
		(0 "F.Cu" signal "TOP")
		(4 "In1.Cu" signal "GND")
		(6 "In2.Cu" signal "IN1")
		(8 "In3.Cu" signal "GND1")
		(10 "In4.Cu" signal "IN2")
		(12 "In5.Cu" signal "GND2")
		(14 "In6.Cu" signal "IN3")
		(16 "In7.Cu" signal "GND3")
		(18 "In8.Cu" signal "VCC")
		(20 "In9.Cu" signal "VCC1")
		(22 "In10.Cu" signal "GND4")
		(24 "In11.Cu" signal "IN4")
		(26 "In12.Cu" signal "GND5")
		(28 "In13.Cu" signal "IN5")
		(30 "In14.Cu" signal "GND6")
		(32 "In15.Cu" signal "IN6")
		(34 "In16.Cu" signal "GND7")
		(2 "B.Cu" signal "BOTTOM")
		(9 "F.Adhes" user "F.Adhesive")
		(11 "B.Adhes" user "B.Adhesive")
		(13 "F.Paste" user "Package Geometry/Pastemask Top")
		(15 "B.Paste" user "Package Geometry/Pastemask Bottom")
		(5 "F.SilkS" user "Ref Des/Silkscreen Top")
		(7 "B.SilkS" user "Ref Des/Silkscreen Bottom")
		(1 "F.Mask" user "Board Geometry/Soldermask Top")
		(3 "B.Mask" user "Board Geometry/Soldermask Bottom")
		(17 "Dwgs.User" user "User.Drawings")
		(19 "Cmts.User" user "User.Comments")
		(21 "Eco1.User" user "User.Eco1")
		(23 "Eco2.User" user "User.Eco2")
		(25 "Edge.Cuts" user "Board Geometry/Outline")
		(27 "Margin" user)
		(31 "F.CrtYd" user "Package Geometry/Place Bound Top")
		(29 "B.CrtYd" user "Package Geometry/Place Bound Bottom")
		(35 "F.Fab" user "Ref Des/Assembly Top")
		(33 "B.Fab" user "Ref Des/Assembly Bottom")
	)
	(footprint ""
		(layer "B.Cu")
		(at 287.899094 -317.876682 180)
		(property "Reference" "R3877"
			(at 0 0 0)
			(layer "B.SilkS")
			(hide yes)
			(effects
				(font
					(size 1.27 1.27)
				)
				(justify mirror)
			)
		)
		(property "Value" ""
			(at 0 0 0)
			(layer "B.Fab")
			(effects
				(font
					(size 1.27 1.27)
				)
				(justify mirror)
			)
		)
		(duplicate_pad_numbers_are_jumpers no)
		(fp_line
			(start 0.7874 0.4064)
			(end 0.7874 -0.4064)
			(stroke
				(width 0.1524)
				(type default)
			)
			(layer "B.SilkS")
		)
		(fp_line
			(start 0.7874 -0.4064)
			(end -0.7874 -0.4064)
			(stroke
				(width 0.1524)
				(type default)
			)
			(layer "B.SilkS")
		)
		(fp_line
			(start -0.7874 0.4064)
			(end 0.7874 0.4064)
			(stroke
				(width 0.1524)
				(type default)
			)
			(layer "B.SilkS")
		)
		(fp_line
			(start -0.7874 -0.4064)
			(end -0.7874 0.4064)
			(stroke
				(width 0.1524)
				(type default)
			)
			(layer "B.SilkS")
		)
		(fp_line
			(start 0.67945 0.3048)
			(end 0.67945 -0.305054)
			(stroke
				(width 0.1)
				(type default)
			)
			(layer "B.Fab")
		)
		(fp_line
			(start 0.67945 -0.305054)
			(end 0.12065 -0.305054)
			(stroke
				(width 0.1)
				(type default)
			)
			(layer "B.Fab")
		)
		(fp_line
			(start 0.12065 0.3048)
			(end 0.67945 0.3048)
			(stroke
				(width 0.1)
				(type default)
			)
			(layer "B.Fab")
		)
		(fp_line
			(start 0.12065 0.2794)
			(end 0.12065 0.3048)
			(stroke
				(width 0.1)
				(type default)
			)
			(layer "B.Fab")
		)
		(fp_line
			(start 0.12065 -0.2794)
			(end -0.12065 -0.2794)
			(stroke
				(width 0.1)
				(type default)
			)
			(layer "B.Fab")
		)
		(fp_line
			(start 0.12065 -0.305054)
			(end 0.12065 -0.2794)
			(stroke
				(width 0.1)
				(type default)
			)
			(layer "B.Fab")
		)
		(fp_line
			(start -0.120396 0.3048)
			(end -0.120396 0.2794)
			(stroke
				(width 0.1)
				(type default)
			)
			(layer "B.Fab")
		)
		(fp_line
			(start -0.120396 0.2794)
			(end 0.12065 0.2794)
			(stroke
				(width 0.1)
				(type default)
			)
			(layer "B.Fab")
		)
		(fp_line
			(start -0.12065 -0.2794)
			(end -0.12065 -0.3048)
			(stroke
				(width 0.1)
				(type default)
			)
			(layer "B.Fab")
		)
		(fp_line
			(start -0.12065 -0.3048)
			(end -0.67945 -0.3048)
			(stroke
				(width 0.1)
				(type default)
			)
			(layer "B.Fab")
		)
		(fp_line
			(start -0.67945 0.3048)
			(end -0.120396 0.3048)
			(stroke
				(width 0.1)
				(type default)
			)
			(layer "B.Fab")
		)
		(fp_line
			(start -0.67945 -0.3048)
			(end -0.67945 0.3048)
			(stroke
				(width 0.1)
				(type default)
			)
			(layer "B.Fab")
		)
		(pad "1" smd circle
			(at 0.40005 0)
			(size 0 0)
			(layers "B.Cu" "B.Mask" "B.Paste")
			(net "I3C_SPD_DDRABCD_CPU0_LVC1_SCL_2")
		)
		(pad "2" smd circle
			(at -0.40005 0)
			(size 0 0)
			(layers "B.Cu" "B.Mask" "B.Paste")
			(net "I3C_SPD_DDRABCD_CPU0_LVC1_SCL")
		)
	)
	(footprint ""
		(layer "B.Cu")
		(at 166.369746 -321.554856 -90)
		(property "Reference" "C94"
			(at 0 0 90)
			(layer "B.SilkS")
			(hide yes)
			(effects
				(font
					(size 1.27 1.27)
				)
				(justify mirror)
			)
		)
		(property "Value" ""
			(at 0 0 90)
			(layer "B.Fab")
			(effects
				(font
					(size 1.27 1.27)
				)
				(justify mirror)
			)
		)
		(duplicate_pad_numbers_are_jumpers no)
		(fp_line
			(start -1.524 0.762)
			(end 1.524 0.762)
			(stroke
				(width 0.1524)
				(type default)
			)
			(layer "B.SilkS")
		)
		(fp_line
			(start 1.524 0.762)
			(end 1.524 -0.762)
			(stroke
				(width 0.1524)
				(type default)
			)
			(layer "B.SilkS")
		)
		(fp_line
			(start -1.524 -0.762)
			(end -1.524 0.762)
			(stroke
				(width 0.1524)
				(type default)
			)
			(layer "B.SilkS")
		)
		(fp_line
			(start 1.524 -0.762)
			(end -1.524 -0.762)
			(stroke
				(width 0.1524)
				(type default)
			)
			(layer "B.SilkS")
		)
		(fp_line
			(start -1.1049 0.724916)
			(end -1.1049 -0.724916)
			(stroke
				(width 0.1)
				(type default)
			)
			(layer "B.Fab")
		)
		(fp_line
			(start 1.1049 0.724916)
			(end -1.1049 0.724916)
			(stroke
				(width 0.1)
				(type default)
			)
			(layer "B.Fab")
		)
		(fp_line
			(start -1.1049 -0.724916)
			(end 1.1049 -0.724916)
			(stroke
				(width 0.1)
				(type default)
			)
			(layer "B.Fab")
		)
		(fp_line
			(start 1.1049 -0.724916)
			(end 1.1049 0.724916)
			(stroke
				(width 0.1)
				(type default)
			)
			(layer "B.Fab")
		)
		(pad "1" smd rect
			(at 0.889 0 270)
			(size 1.016 1.27)
			(layers "B.Cu" "B.Mask" "B.Paste")
			(net "P12V_S3_AUX_CPU1_NVDIMM")
		)
		(pad "2" smd rect
			(at -0.889 0 270)
			(size 1.016 1.27)
			(layers "B.Cu" "B.Mask" "B.Paste")
			(net "GND")
		)
	)
	(footprint ""
		(layer "B.Cu")
		(at 116.40312 -244.82044 -90)
		(property "Reference" "C320"
			(at 0 0 90)
			(layer "B.SilkS")
			(hide yes)
			(effects
				(font
					(size 1.27 1.27)
				)
				(justify mirror)
			)
		)
		(property "Value" ""
			(at 0 0 90)
			(layer "B.Fab")
			(effects
				(font
					(size 1.27 1.27)
				)
				(justify mirror)
			)
		)
		(duplicate_pad_numbers_are_jumpers no)
		(fp_line
			(start -1.524 0.762)
			(end 1.524 0.762)
			(stroke
				(width 0.1524)
				(type default)
			)
			(layer "B.SilkS")
		)
		(fp_line
			(start 1.524 0.762)
			(end 1.524 -0.762)
			(stroke
				(width 0.1524)
				(type default)
			)
			(layer "B.SilkS")
		)
		(fp_line
			(start -1.524 -0.762)
			(end -1.524 0.762)
			(stroke
				(width 0.1524)
				(type default)
			)
			(layer "B.SilkS")
		)
		(fp_line
			(start 1.524 -0.762)
			(end -1.524 -0.762)
			(stroke
				(width 0.1524)
				(type default)
			)
			(layer "B.SilkS")
		)
		(fp_line
			(start -1.1049 0.724916)
			(end -1.1049 -0.724916)
			(stroke
				(width 0.1)
				(type default)
			)
			(layer "B.Fab")
		)
		(fp_line
			(start 1.1049 0.724916)
			(end -1.1049 0.724916)
			(stroke
				(width 0.1)
				(type default)
			)
			(layer "B.Fab")
		)
		(fp_line
			(start -1.1049 -0.724916)
			(end 1.1049 -0.724916)
			(stroke
				(width 0.1)
				(type default)
			)
			(layer "B.Fab")
		)
		(fp_line
			(start 1.1049 -0.724916)
			(end 1.1049 0.724916)
			(stroke
				(width 0.1)
				(type default)
			)
			(layer "B.Fab")
		)
		(pad "1" smd rect
			(at 0.889 0 270)
			(size 1.016 1.27)
			(layers "B.Cu" "B.Mask" "B.Paste")
			(net "PVCCIN_CPU1")
		)
		(pad "2" smd rect
			(at -0.889 0 270)
			(size 1.016 1.27)
			(layers "B.Cu" "B.Mask" "B.Paste")
			(net "GND")
		)
	)
)
